(kicad_pcb
	(version 20260206)
	(generator "pcbnew")
	(generator_version "10.0")
	(general
		(thickness 1.6)
		(legacy_teardrops no)
	)
	(paper "A4")
	(title_block
		(title "Wiwynn_Tioga_Pass_MB.brd")
		(comment 1 "Tioga Pass / footprints 4031-4038 of 4770")
	)
	(layers
		(0 "F.Cu" signal "TOP")
		(4 "In1.Cu" signal "L2GND")
		(6 "In2.Cu" signal "L3")
		(8 "In3.Cu" signal "L4GND")
		(10 "In4.Cu" signal "L5")
		(12 "In5.Cu" signal "L6GND")
		(14 "In6.Cu" signal "L7VCC")
		(16 "In7.Cu" signal "L8VCC")
		(18 "In8.Cu" signal "L9GND")
		(20 "In9.Cu" signal "L10")
		(22 "In10.Cu" signal "L11GND")
		(24 "In11.Cu" signal "L12")
		(26 "In12.Cu" signal "L13GND")
		(2 "B.Cu" signal "BOTTOM")
		(9 "F.Adhes" user "F.Adhesive")
		(11 "B.Adhes" user "B.Adhesive")
		(13 "F.Paste" user "Package Geometry/Pastemask Top")
		(15 "B.Paste" user "Package Geometry/Pastemask Bottom")
		(5 "F.SilkS" user "Ref Des/Silkscreen Top")
		(7 "B.SilkS" user "Ref Des/Silkscreen Bottom")
		(1 "F.Mask" user "Board Geometry/Soldermask Top")
		(3 "B.Mask" user "Board Geometry/Soldermask Bottom")
		(17 "Dwgs.User" user "User.Drawings")
		(19 "Cmts.User" user "User.Comments")
		(21 "Eco1.User" user "User.Eco1")
		(23 "Eco2.User" user "User.Eco2")
		(25 "Edge.Cuts" user "Board Geometry/Outline")
		(27 "Margin" user)
		(31 "F.CrtYd" user "Package Geometry/Place Bound Top")
		(29 "B.CrtYd" user "Package Geometry/Place Bound Bottom")
		(35 "F.Fab" user "Ref Des/Assembly Top")
		(33 "B.Fab" user "Ref Des/Assembly Bottom")
	)
	(footprint ""
		(layer "B.Cu")
		(at 176.212754 -85.217 -90)
		(property "Reference" "R6P9"
			(at 0 0 90)
			(layer "B.SilkS")
			(hide yes)
			(effects
				(font
					(size 1.27 1.27)
				)
				(justify mirror)
			)
		)
		(property "Value" ""
			(at 0 0 90)
			(layer "B.Fab")
			(effects
				(font
					(size 1.27 1.27)
				)
				(justify mirror)
			)
		)
		(duplicate_pad_numbers_are_jumpers no)
		(fp_poly
			(pts
				(xy 0.2794 -0.1016) (xy -0.2794 -0.1016) (xy -0.2794 0.9906) (xy 0.2794 0.9906)
			)
			(stroke
				(width 0)
				(type default)
			)
			(fill no)
			(layer "B.CrtYd")
		)
		(fp_line
			(start -0.2794 0.9906)
			(end -0.2794 -0.1016)
			(stroke
				(width 0.1)
				(type default)
			)
			(layer "B.Fab")
		)
		(fp_line
			(start 0.2794 0.9906)
			(end -0.2794 0.9906)
			(stroke
				(width 0.1)
				(type default)
			)
			(layer "B.Fab")
		)
		(fp_line
			(start -0.2794 -0.1016)
			(end 0.2794 -0.1016)
			(stroke
				(width 0.1)
				(type default)
			)
			(layer "B.Fab")
		)
		(fp_line
			(start 0.2794 -0.1016)
			(end 0.2794 0.9906)
			(stroke
				(width 0.1)
				(type default)
			)
			(layer "B.Fab")
		)
		(pad "1" smd rect
			(at 0 0 90)
			(size 0.508 0.508)
			(layers "B.Cu" "B.Mask" "B.Paste")
			(net "CLK_100M_CPU0_PE_REFCLK_DN")
		)
		(pad "2" smd rect
			(at 0 0.889 90)
			(size 0.508 0.508)
			(layers "B.Cu" "B.Mask" "B.Paste")
			(net "GND")
		)
		(zone
			(layer "B.Cu")
			(hatch none 0.5)
			(connect_pads
				(clearance 0)
			)
			(min_thickness 0.25)
			(keepout
				(tracks not_allowed)
				(vias allowed)
				(pads allowed)
				(copperpour not_allowed)
				(footprints allowed)
			)
			(placement
				(enabled no)
				(sheetname "")
			)
			(fill
				(thermal_gap 0.5)
				(thermal_bridge_width 0.5)
				(island_removal_mode 0)
			)
			(polygon
				(pts
					(xy 175.577754 -84.963) (xy 175.577754 -85.471) (xy 175.958754 -85.471) (xy 175.958754 -84.963)
				)
			)
		)
		(zone
			(layer "B.Cu")
			(hatch none 0.5)
			(connect_pads
				(clearance 0)
			)
			(min_thickness 0.25)
			(keepout
				(tracks allowed)
				(vias not_allowed)
				(pads allowed)
				(copperpour not_allowed)
				(footprints allowed)
			)
			(placement
				(enabled no)
				(sheetname "")
			)
			(fill
				(thermal_gap 0.5)
				(thermal_bridge_width 0.5)
				(island_removal_mode 0)
			)
			(polygon
				(pts
					(xy 175.958754 -84.963) (xy 175.958754 -85.471) (xy 175.577754 -85.471) (xy 175.577754 -84.963)
				)
			)
		)
	)
	(footprint ""
		(layer "B.Cu")
		(at 372.5418 -90.805 90)
		(property "Reference" "R7D23"
			(at 0 0 90)
			(layer "B.SilkS")
			(hide yes)
			(effects
				(font
					(size 1.27 1.27)
				)
				(justify mirror)
			)
		)
		(property "Value" ""
			(at 0 0 90)
			(layer "B.Fab")
			(effects
				(font
					(size 1.27 1.27)
				)
				(justify mirror)
			)
		)
		(duplicate_pad_numbers_are_jumpers no)
		(fp_poly
			(pts
				(xy 0.2794 -0.1016) (xy -0.2794 -0.1016) (xy -0.2794 0.9906) (xy 0.2794 0.9906)
			)
			(stroke
				(width 0)
				(type default)
			)
			(fill no)
			(layer "B.CrtYd")
		)
		(fp_line
			(start 0.2794 -0.1016)
			(end 0.2794 0.9906)
			(stroke
				(width 0.1)
				(type default)
			)
			(layer "B.Fab")
		)
		(fp_line
			(start -0.2794 -0.1016)
			(end 0.2794 -0.1016)
			(stroke
				(width 0.1)
				(type default)
			)
			(layer "B.Fab")
		)
		(fp_line
			(start 0.2794 0.9906)
			(end -0.2794 0.9906)
			(stroke
				(width 0.1)
				(type default)
			)
			(layer "B.Fab")
		)
		(fp_line
			(start -0.2794 0.9906)
			(end -0.2794 -0.1016)
			(stroke
				(width 0.1)
				(type default)
			)
			(layer "B.Fab")
		)
		(pad "1" smd rect
			(at 0 0 270)
			(size 0.508 0.508)
			(layers "B.Cu" "B.Mask" "B.Paste")
			(net "RST_BMC_SRST_N")
		)
		(pad "2" smd rect
			(at 0 0.889 270)
			(size 0.508 0.508)
			(layers "B.Cu" "B.Mask" "B.Paste")
			(net "RST_BMC_SRST_R_N")
		)
		(zone
			(layer "B.Cu")
			(hatch none 0.5)
			(connect_pads
				(clearance 0)
			)
			(min_thickness 0.25)
			(keepout
				(tracks allowed)
				(vias not_allowed)
				(pads allowed)
				(copperpour not_allowed)
				(footprints allowed)
			)
			(placement
				(enabled no)
				(sheetname "")
			)
			(fill
				(thermal_gap 0.5)
				(thermal_bridge_width 0.5)
				(island_removal_mode 0)
			)
			(polygon
				(pts
					(xy 372.7958 -91.059) (xy 372.7958 -90.551) (xy 373.1768 -90.551) (xy 373.1768 -91.059)
				)
			)
		)
		(zone
			(layer "B.Cu")
			(hatch none 0.5)
			(connect_pads
				(clearance 0)
			)
			(min_thickness 0.25)
			(keepout
				(tracks not_allowed)
				(vias allowed)
				(pads allowed)
				(copperpour not_allowed)
				(footprints allowed)
			)
			(placement
				(enabled no)
				(sheetname "")
			)
			(fill
				(thermal_gap 0.5)
				(thermal_bridge_width 0.5)
				(island_removal_mode 0)
			)
			(polygon
				(pts
					(xy 373.1768 -91.059) (xy 373.1768 -90.551) (xy 372.7958 -90.551) (xy 372.7958 -91.059)
				)
			)
		)
	)
	(footprint ""
		(layer "B.Cu")
		(at 177.1015 -57.531 -90)
		(property "Reference" "C4E28"
			(at 0 0 90)
			(layer "B.SilkS")
			(hide yes)
			(effects
				(font
					(size 1.27 1.27)
				)
				(justify mirror)
			)
		)
		(property "Value" "*"
			(at -1.1811 -2.8194 270)
			(unlocked yes)
			(layer "B.Fab")
			(hide yes)
			(effects
				(font
					(size 1.27 1.016)
					(thickness 0.1524)
				)
				(justify mirror)
			)
		)
		(property "Device Type" "SC1U10V2KX-4-GP_SMD-BCG6-SC1U1A"
			(at -1.1811 -4.3434 270)
			(unlocked yes)
			(layer "B.Fab")
			(hide yes)
			(effects
				(font
					(size 1.27 1.016)
					(thickness 0.1524)
				)
				(justify mirror)
			)
		)
		(duplicate_pad_numbers_are_jumpers no)
		(fp_rect
			(start 0.4318 0.9525)
			(end -0.4318 -0.9525)
			(stroke
				(width 0)
				(type default)
			)
			(fill no)
			(layer "B.CrtYd")
		)
		(fp_rect
			(start 0.4318 0.9525)
			(end -0.4318 -0.9525)
			(stroke
				(width 0)
				(type default)
			)
			(fill no)
			(layer "B.Fab")
		)
		(pad "1" smd custom
			(at 0 -0.4445 90)
			(size 0.1524 0.1524)
			(layers "B.Cu" "B.Mask" "B.Paste")
			(net "P5V_STBY")
			(options
				(clearance outline)
				(anchor circle)
			)
			(primitives
				(gr_poly
					(pts
						(arc
							(start 0.3048 0.2032)
							(mid 0.275042 0.275042)
							(end 0.2032 0.3048)
						)
						(arc
							(start -0.2032 0.3048)
							(mid -0.275042 0.275042)
							(end -0.3048 0.2032)
						)
						(arc
							(start -0.3048 -0.2032)
							(mid -0.275042 -0.275042)
							(end -0.2032 -0.3048)
						)
						(arc
							(start 0.2032 -0.3048)
							(mid 0.275042 -0.275042)
							(end 0.3048 -0.2032)
						)
					)
					(width 0)
					(fill yes)
				)
			)
		)
		(pad "2" smd custom
			(at 0 0.4445 90)
			(size 0.1524 0.1524)
			(layers "B.Cu" "B.Mask" "B.Paste")
			(net "GND")
			(options
				(clearance outline)
				(anchor circle)
			)
			(primitives
				(gr_poly
					(pts
						(arc
							(start 0.3048 0.2032)
							(mid 0.275042 0.275042)
							(end 0.2032 0.3048)
						)
						(arc
							(start -0.2032 0.3048)
							(mid -0.275042 0.275042)
							(end -0.3048 0.2032)
						)
						(arc
							(start -0.3048 -0.2032)
							(mid -0.275042 -0.275042)
							(end -0.2032 -0.3048)
						)
						(arc
							(start 0.2032 -0.3048)
							(mid 0.275042 -0.275042)
							(end 0.3048 -0.2032)
						)
					)
					(width 0)
					(fill yes)
				)
			)
		)
	)
	(footprint ""
		(layer "B.Cu")
		(at 411.48 0.2794)
		(property "Reference" "U8G2"
			(at -5.334 1.24333 180)
			(unlocked yes)
			(layer "B.SilkS")
			(effects
				(font
					(size 0.7874 0.5842)
					(thickness 0.1524)
				)
				(justify left mirror)
			)
		)
		(property "Value" ""
			(at 0 0 0)
			(layer "B.Fab")
			(effects
				(font
					(size 1.27 1.27)
				)
				(justify mirror)
			)
		)
		(duplicate_pad_numbers_are_jumpers no)
		(fp_circle
			(center 1.03124 -0.04826)
			(end 1.15824 -0.04826)
			(stroke
				(width 0.254)
				(type default)
			)
			(fill no)
			(layer "B.SilkS")
		)
		(fp_poly
			(pts
				(xy -0.21463 -0.450088) (xy -1.56337 -0.450088) (xy -1.56337 1.75006) (xy -0.21463 1.75006)
			)
			(stroke
				(width 0)
				(type default)
			)
			(fill no)
			(layer "B.CrtYd")
		)
		(fp_line
			(start -1.56337 -0.450088)
			(end -1.56337 1.75006)
			(stroke
				(width 0.1)
				(type default)
			)
			(layer "B.Fab")
		)
		(fp_line
			(start -1.56337 1.75006)
			(end -0.21463 1.75006)
			(stroke
				(width 0.1)
				(type default)
			)
			(layer "B.Fab")
		)
		(fp_line
			(start -0.21463 -0.450088)
			(end -1.56337 -0.450088)
			(stroke
				(width 0.1)
				(type default)
			)
			(layer "B.Fab")
		)
		(fp_line
			(start -0.21463 1.75006)
			(end -0.21463 -0.450088)
			(stroke
				(width 0.1)
				(type default)
			)
			(layer "B.Fab")
		)
		(fp_circle
			(center 0.4699 -0.8382)
			(end 0.5969 -0.8382)
			(stroke
				(width 0.254)
				(type default)
			)
			(fill no)
			(layer "B.Fab")
		)
		(pad "1" smd rect
			(at 0 0 180)
			(size 1.016 0.381)
			(layers "B.Cu" "B.Mask" "B.Paste")
			(net "Net_6469")
		)
		(pad "2" smd rect
			(at 0 0.649986 180)
			(size 1.016 0.381)
			(layers "B.Cu" "B.Mask" "B.Paste")
			(net "FAN_PWM_OUT_SYS0")
		)
		(pad "3" smd rect
			(at 0 1.299972 180)
			(size 1.016 0.381)
			(layers "B.Cu" "B.Mask" "B.Paste")
			(net "GND")
		)
		(pad "4" smd rect
			(at -1.778 1.299972 180)
			(size 1.016 0.381)
			(layers "B.Cu" "B.Mask" "B.Paste")
			(net "FAN_PWM_OUT_SYS0_BUF")
		)
		(pad "5" smd rect
			(at -1.778 0 180)
			(size 1.016 0.381)
			(layers "B.Cu" "B.Mask" "B.Paste")
			(net "P3V3_STBY")
		)
	)
	(footprint ""
		(layer "B.Cu")
		(at 413.270446 -39.735252 -90)
		(property "Reference" "FB2T4"
			(at 0 0 90)
			(layer "B.SilkS")
			(hide yes)
			(effects
				(font
					(size 1.27 1.27)
				)
				(justify mirror)
			)
		)
		(property "Value" "*"
			(at -0.0254 -2.8829 270)
			(unlocked yes)
			(layer "B.Fab")
			(hide yes)
			(effects
				(font
					(size 1.27 1.016)
					(thickness 0.1524)
				)
				(justify mirror)
			)
		)
		(property "Device Type" "HCB1608KF-800T30-GP_DISCRET-G9A"
			(at -0.0254 -4.4069 270)
			(unlocked yes)
			(layer "B.Fab")
			(hide yes)
			(effects
				(font
					(size 1.27 1.016)
					(thickness 0.1524)
				)
				(justify mirror)
			)
		)
		(duplicate_pad_numbers_are_jumpers no)
		(fp_line
			(start -0.254 0)
			(end 0.254 0)
			(stroke
				(width 0.2032)
				(type default)
			)
			(layer "B.SilkS")
		)
		(fp_rect
			(start 0.5842 1.3335)
			(end -0.5842 -1.3335)
			(stroke
				(width 0)
				(type default)
			)
			(fill no)
			(layer "B.CrtYd")
		)
		(fp_rect
			(start 0.5842 1.3335)
			(end -0.5842 -1.3335)
			(stroke
				(width 0)
				(type default)
			)
			(fill no)
			(layer "B.Fab")
		)
		(pad "1" smd custom
			(at 0 -0.762 90)
			(size 0.2159 0.2159)
			(layers "B.Cu" "B.Mask" "B.Paste")
			(net "P3V3_STBY")
			(options
				(clearance outline)
				(anchor circle)
			)
			(primitives
				(gr_poly
					(pts
						(arc
							(start -0.3302 0.4318)
							(mid -0.402042 0.402042)
							(end -0.4318 0.3302)
						)
						(arc
							(start -0.4318 -0.3302)
							(mid -0.402042 -0.402042)
							(end -0.3302 -0.4318)
						)
						(arc
							(start 0.3302 -0.4318)
							(mid 0.402042 -0.402042)
							(end 0.4318 -0.3302)
						)
						(arc
							(start 0.4318 0.3302)
							(mid 0.402042 0.402042)
							(end 0.3302 0.4318)
						)
					)
					(width 0)
					(fill yes)
				)
			)
		)
		(pad "2" smd custom
			(at 0 0.762 90)
			(size 0.2159 0.2159)
			(layers "B.Cu" "B.Mask" "B.Paste")
			(net "VCC_D_3V3")
			(options
				(clearance outline)
				(anchor circle)
			)
			(primitives
				(gr_poly
					(pts
						(arc
							(start -0.3302 0.4318)
							(mid -0.402042 0.402042)
							(end -0.4318 0.3302)
						)
						(arc
							(start -0.4318 -0.3302)
							(mid -0.402042 -0.402042)
							(end -0.3302 -0.4318)
						)
						(arc
							(start 0.3302 -0.4318)
							(mid 0.402042 -0.402042)
							(end 0.4318 -0.3302)
						)
						(arc
							(start 0.4318 0.3302)
							(mid 0.402042 0.402042)
							(end 0.3302 0.4318)
						)
					)
					(width 0)
					(fill yes)
				)
			)
		)
	)
	(footprint ""
		(layer "B.Cu")
		(at 356.08768 -96.062292 90)
		(property "Reference" "C7C8"
			(at 0 0 90)
			(layer "B.SilkS")
			(hide yes)
			(effects
				(font
					(size 1.27 1.27)
				)
				(justify mirror)
			)
		)
		(property "Value" "*"
			(at 0.0762 -6.2357 90)
			(unlocked yes)
			(layer "B.Fab")
			(hide yes)
			(effects
				(font
					(size 1.27 1.016)
					(thickness 0.1524)
				)
				(justify mirror)
			)
		)
		(property "Device Type" "SC22U16V5MX-4-GP_SMD-BCG5-SC22A"
			(at 0.0762 -8.2677 90)
			(unlocked yes)
			(layer "B.Fab")
			(hide yes)
			(effects
				(font
					(size 1.27 1.016)
					(thickness 0.1524)
				)
				(justify mirror)
			)
		)
		(duplicate_pad_numbers_are_jumpers no)
		(fp_line
			(start -0.635 0)
			(end 0.635 0)
			(stroke
				(width 0.508)
				(type default)
			)
			(layer "B.SilkS")
		)
		(fp_rect
			(start 0.9652 1.778)
			(end -0.9652 -1.778)
			(stroke
				(width 0)
				(type default)
			)
			(fill no)
			(layer "B.CrtYd")
		)
		(fp_poly
			(pts
				(xy 0.9652 -1.778) (xy -0.9652 -1.778) (xy -0.9652 1.778) (xy 0.9652 1.778)
			)
			(stroke
				(width 0)
				(type default)
			)
			(fill no)
			(layer "B.Fab")
		)
		(pad "1" smd rect
			(at 0 -0.9652 270)
			(size 1.397 1.143)
			(layers "B.Cu" "B.Mask" "B.Paste")
			(net "VR_FET_SW_P12V_STBY_PVCCIO_CPU0")
		)
		(pad "2" smd rect
			(at 0 0.9652 270)
			(size 1.397 1.143)
			(layers "B.Cu" "B.Mask" "B.Paste")
			(net "GND")
		)
	)
	(footprint ""
		(layer "B.Cu")
		(at 468.58809 -6.011672)
		(property "Reference" "R7E21"
			(at 0 0 0)
			(layer "B.SilkS")
			(hide yes)
			(effects
				(font
					(size 1.27 1.27)
				)
				(justify mirror)
			)
		)
		(property "Value" ""
			(at 0 0 0)
			(layer "B.Fab")
			(effects
				(font
					(size 1.27 1.27)
				)
				(justify mirror)
			)
		)
		(duplicate_pad_numbers_are_jumpers no)
		(fp_poly
			(pts
				(xy 0.2794 -0.1016) (xy -0.2794 -0.1016) (xy -0.2794 0.9906) (xy 0.2794 0.9906)
			)
			(stroke
				(width 0)
				(type default)
			)
			(fill no)
			(layer "B.CrtYd")
		)
		(fp_line
			(start -0.2794 -0.1016)
			(end 0.2794 -0.1016)
			(stroke
				(width 0.1)
				(type default)
			)
			(layer "B.Fab")
		)
		(fp_line
			(start -0.2794 0.9906)
			(end -0.2794 -0.1016)
			(stroke
				(width 0.1)
				(type default)
			)
			(layer "B.Fab")
		)
		(fp_line
			(start 0.2794 -0.1016)
			(end 0.2794 0.9906)
			(stroke
				(width 0.1)
				(type default)
			)
			(layer "B.Fab")
		)
		(fp_line
			(start 0.2794 0.9906)
			(end -0.2794 0.9906)
			(stroke
				(width 0.1)
				(type default)
			)
			(layer "B.Fab")
		)
		(pad "1" smd rect
			(at 0 0 180)
			(size 0.508 0.508)
			(layers "B.Cu" "B.Mask" "B.Paste")
			(net "P3V3")
		)
		(pad "2" smd rect
			(at 0 0.889 180)
			(size 0.508 0.508)
			(layers "B.Cu" "B.Mask" "B.Paste")
			(net "FM_PWRBRK_N")
		)
		(zone
			(layer "B.Cu")
			(hatch none 0.5)
			(connect_pads
				(clearance 0)
			)
			(min_thickness 0.25)
			(keepout
				(tracks allowed)
				(vias not_allowed)
				(pads allowed)
				(copperpour not_allowed)
				(footprints allowed)
			)
			(placement
				(enabled no)
				(sheetname "")
			)
			(fill
				(thermal_gap 0.5)
				(thermal_bridge_width 0.5)
				(island_removal_mode 0)
			)
			(polygon
				(pts
					(xy 468.84209 -5.757672) (xy 468.33409 -5.757672) (xy 468.33409 -5.376672) (xy 468.84209 -5.376672)
				)
			)
		)
		(zone
			(layer "B.Cu")
			(hatch none 0.5)
			(connect_pads
				(clearance 0)
			)
			(min_thickness 0.25)
			(keepout
				(tracks not_allowed)
				(vias allowed)
				(pads allowed)
				(copperpour not_allowed)
				(footprints allowed)
			)
			(placement
				(enabled no)
				(sheetname "")
			)
			(fill
				(thermal_gap 0.5)
				(thermal_bridge_width 0.5)
				(island_removal_mode 0)
			)
			(polygon
				(pts
					(xy 468.84209 -5.376672) (xy 468.33409 -5.376672) (xy 468.33409 -5.757672) (xy 468.84209 -5.757672)
				)
			)
		)
	)
	(footprint ""
		(layer "B.Cu")
		(at 375.991374 -83.86953 -90)
		(property "Reference" "Q7D1"
			(at 0.229362 -1.2065 270)
			(unlocked yes)
			(layer "B.SilkS")
			(effects
				(font
					(size 0.4064 0.254)
					(thickness 0.1524)
				)
				(justify left mirror)
			)
		)
		(property "Value" ""
			(at 0 0 90)
			(layer "B.Fab")
			(effects
				(font
					(size 1.27 1.27)
				)
				(justify mirror)
			)
		)
		(duplicate_pad_numbers_are_jumpers no)
		(fp_line
			(start -1.778 2.4765)
			(end -1.778 1.5875)
			(stroke
				(width 0.1524)
				(type default)
			)
			(layer "B.SilkS")
		)
		(fp_line
			(start -0.9525 2.4765)
			(end -1.778 2.4765)
			(stroke
				(width 0.1524)
				(type default)
			)
			(layer "B.SilkS")
		)
		(fp_line
			(start -0.381 0.635)
			(end -0.381 1.27)
			(stroke
				(width 0.1524)
				(type default)
			)
			(layer "B.SilkS")
		)
		(fp_line
			(start -1.778 -0.5715)
			(end -1.778 0.3175)
			(stroke
				(width 0.1524)
				(type default)
			)
			(layer "B.SilkS")
		)
		(fp_line
			(start -0.9525 -0.5715)
			(end -1.778 -0.5715)
			(stroke
				(width 0.1524)
				(type default)
			)
			(layer "B.SilkS")
		)
		(fp_circle
			(center 0.9525 -0.9271)
			(end 0.9525 -1.0541)
			(stroke
				(width 0.254)
				(type default)
			)
			(fill no)
			(layer "B.SilkS")
		)
		(fp_poly
			(pts
				(xy -1.778 2.4765) (xy -0.381 2.4765) (xy -0.381 -0.5715) (xy -1.778 -0.5715)
			)
			(stroke
				(width 0)
				(type default)
			)
			(fill no)
			(layer "B.CrtYd")
		)
		(fp_line
			(start -1.778 2.4765)
			(end -1.778 -0.5715)
			(stroke
				(width 0.1)
				(type default)
			)
			(layer "B.Fab")
		)
		(fp_line
			(start -0.381 2.4765)
			(end -1.778 2.4765)
			(stroke
				(width 0.1)
				(type default)
			)
			(layer "B.Fab")
		)
		(fp_line
			(start -1.778 -0.5715)
			(end -0.381 -0.5715)
			(stroke
				(width 0.1)
				(type default)
			)
			(layer "B.Fab")
		)
		(fp_line
			(start -0.381 -0.5715)
			(end -0.381 2.4765)
			(stroke
				(width 0.1)
				(type default)
			)
			(layer "B.Fab")
		)
		(fp_circle
			(center 0.9525 -0.9271)
			(end 0.9525 -1.0541)
			(stroke
				(width 0.254)
				(type default)
			)
			(fill no)
			(layer "B.Fab")
		)
		(pad "1" smd rect
			(at 0 0 90)
			(size 1.143 0.508)
			(layers "B.Cu" "B.Mask" "B.Paste")
			(net "FM_THERMTRIP_DLY_R")
		)
		(pad "2" smd rect
			(at 0 1.905 90)
			(size 1.143 0.508)
			(layers "B.Cu" "B.Mask" "B.Paste")
			(net "GND")
		)
		(pad "3" smd rect
			(at -2.159 0.9525 90)
			(size 1.143 0.508)
			(layers "B.Cu" "B.Mask" "B.Paste")
			(net "FM_PCH_LVC1_THERMTRIP_N")
		)
	)
)
